(kicad_pcb
	(version 20260206)
	(generator "pcbnew")
	(generator_version "10.0")
	(general
		(thickness 1.6)
		(legacy_teardrops no)
	)
	(paper "A4")
	(title_block
		(title "dpb — 14545-sa.0730WZS0815.brd")
		(comment 1 "Honey Badger (Wiwynn) / footprints 636-642 of 1066")
	)
	(layers
		(0 "F.Cu" signal "TOP")
		(4 "In1.Cu" signal "L2GND")
		(6 "In2.Cu" signal "L3")
		(8 "In3.Cu" signal "L4VCC")
		(10 "In4.Cu" signal "L5VCC")
		(12 "In5.Cu" signal "L6")
		(14 "In6.Cu" signal "L7GND")
		(2 "B.Cu" signal "BOTTOM")
		(9 "F.Adhes" user "F.Adhesive")
		(11 "B.Adhes" user "B.Adhesive")
		(13 "F.Paste" user "Package Geometry/Pastemask Top")
		(15 "B.Paste" user "Package Geometry/Pastemask Bottom")
		(5 "F.SilkS" user "Ref Des/Silkscreen Top")
		(7 "B.SilkS" user "Ref Des/Silkscreen Bottom")
		(1 "F.Mask" user "Board Geometry/Soldermask Top")
		(3 "B.Mask" user "Board Geometry/Soldermask Bottom")
		(17 "Dwgs.User" user "User.Drawings")
		(19 "Cmts.User" user "User.Comments")
		(21 "Eco1.User" user "User.Eco1")
		(23 "Eco2.User" user "User.Eco2")
		(25 "Edge.Cuts" user "Board Geometry/Outline")
		(27 "Margin" user)
		(31 "F.CrtYd" user "Package Geometry/Place Bound Top")
		(29 "B.CrtYd" user "Package Geometry/Place Bound Bottom")
		(35 "F.Fab" user "Ref Des/Assembly Top")
		(33 "B.Fab" user "Ref Des/Assembly Bottom")
	)
	(footprint ""
		(layer "F.Cu")
		(at 41.655746 -326.926702)
		(property "Reference" "Q23"
			(at 0 0 0)
			(layer "F.SilkS")
			(hide yes)
			(effects
				(font
					(size 1.27 1.27)
				)
			)
		)
		(property "Value" "AO4406AL-GP"
			(at -3.707384 -1.5367 0)
			(unlocked yes)
			(layer "F.Fab")
			(hide yes)
			(effects
				(font
					(size 1.016 1.016)
					(thickness 0.1524)
				)
			)
		)
		(property "Device Type" "SOIC8H69"
			(at -3.707384 -3.0607 0)
			(unlocked yes)
			(layer "F.Fab")
			(hide yes)
			(effects
				(font
					(size 1.016 1.016)
					(thickness 0.1524)
				)
			)
		)
		(duplicate_pad_numbers_are_jumpers no)
		(fp_line
			(start -2.7432 -1.4224)
			(end -2.7432 1.4224)
			(stroke
				(width 0.1524)
				(type default)
			)
			(layer "F.SilkS")
		)
		(fp_line
			(start -2.7432 1.4224)
			(end -2.6416 1.4224)
			(stroke
				(width 0.1524)
				(type default)
			)
			(layer "F.SilkS")
		)
		(fp_line
			(start -2.7432 1.4224)
			(end 2.1336 1.4224)
			(stroke
				(width 0.1524)
				(type default)
			)
			(layer "F.SilkS")
		)
		(fp_line
			(start -2.7178 -0.508)
			(end -2.1844 -0.0508)
			(stroke
				(width 0.1524)
				(type default)
			)
			(layer "F.SilkS")
		)
		(fp_line
			(start -2.6289 3.4417)
			(end -2.6289 1.4732)
			(stroke
				(width 0.381)
				(type default)
			)
			(layer "F.SilkS")
		)
		(fp_line
			(start -2.1844 -0.0508)
			(end -2.7178 0.508)
			(stroke
				(width 0.1524)
				(type default)
			)
			(layer "F.SilkS")
		)
		(fp_line
			(start 2.1336 -1.4224)
			(end -2.7432 -1.4224)
			(stroke
				(width 0.1524)
				(type default)
			)
			(layer "F.SilkS")
		)
		(fp_line
			(start 2.1336 1.4224)
			(end 2.1336 -1.4224)
			(stroke
				(width 0.1524)
				(type default)
			)
			(layer "F.SilkS")
		)
		(fp_poly
			(pts
				(xy -2.2098 -1.4224) (xy -2.2098 1.4224) (xy 2.2098 1.4224) (xy 2.2098 -1.4224)
			)
			(stroke
				(width 0)
				(type default)
			)
			(fill yes)
			(layer "F.SilkS")
		)
		(fp_rect
			(start -2.450084 2.999994)
			(end 2.450084 -2.999994)
			(stroke
				(width 0)
				(type default)
			)
			(fill no)
			(layer "F.CrtYd")
		)
		(fp_poly
			(pts
				(xy -2.8194 3.6322) (xy -2.8194 -3.6322) (xy 2.8194 -3.6322) (xy 2.8194 1.18364) (xy 2.450084 1.18364)
				(xy 2.450084 -2.999994) (xy -2.450084 -2.999994) (xy -2.450084 2.999994) (xy 2.450084 2.999994)
				(xy 2.450084 1.18618) (xy 2.8194 1.18618) (xy 2.8194 3.6322)
			)
			(stroke
				(width 0)
				(type default)
			)
			(fill no)
			(layer "F.CrtYd")
		)
		(fp_rect
			(start -2.8194 3.6322)
			(end 2.8194 -3.6322)
			(stroke
				(width 0)
				(type default)
			)
			(fill no)
			(layer "F.Fab")
		)
		(pad "1" smd rect
			(at -1.905 2.54)
			(size 0.635 1.651)
			(layers "F.Cu" "F.Mask" "F.Paste")
			(net "P5V_HDD11")
		)
		(pad "2" smd rect
			(at -0.635 2.54)
			(size 0.635 1.651)
			(layers "F.Cu" "F.Mask" "F.Paste")
			(net "P5V_HDD11")
		)
		(pad "3" smd rect
			(at 0.635 2.54)
			(size 0.635 1.651)
			(layers "F.Cu" "F.Mask" "F.Paste")
			(net "P5V_HDD11")
		)
		(pad "4" smd rect
			(at 1.905 2.54)
			(size 0.635 1.651)
			(layers "F.Cu" "F.Mask" "F.Paste")
			(net "SW_HDD11_P")
		)
		(pad "5" smd rect
			(at 1.905 -2.54)
			(size 0.635 1.651)
			(layers "F.Cu" "F.Mask" "F.Paste")
			(net "P5VC")
		)
		(pad "6" smd rect
			(at 0.635 -2.54)
			(size 0.635 1.651)
			(layers "F.Cu" "F.Mask" "F.Paste")
			(net "P5VC")
		)
		(pad "7" smd rect
			(at -0.635 -2.54)
			(size 0.635 1.651)
			(layers "F.Cu" "F.Mask" "F.Paste")
			(net "P5VC")
		)
		(pad "8" smd rect
			(at -1.905 -2.54)
			(size 0.635 1.651)
			(layers "F.Cu" "F.Mask" "F.Paste")
			(net "P5VC")
		)
	)
	(footprint ""
		(layer "F.Cu")
		(at 95.757746 -13.4747 90)
		(property "Reference" "R476"
			(at 0 0 90)
			(layer "F.SilkS")
			(hide yes)
			(effects
				(font
					(size 1.27 1.27)
				)
			)
		)
		(property "Value" "4K7R2J-2-GP"
			(at 0.064008 -3.993896 90)
			(unlocked yes)
			(layer "F.Fab")
			(hide yes)
			(effects
				(font
					(size 1.016 1.016)
					(thickness 0.1524)
				)
			)
		)
		(property "Device Type" "R402H16"
			(at 0.064008 -5.517896 90)
			(unlocked yes)
			(layer "F.Fab")
			(hide yes)
			(effects
				(font
					(size 1.016 1.016)
					(thickness 0.1524)
				)
			)
		)
		(duplicate_pad_numbers_are_jumpers no)
		(fp_line
			(start 0.508 -0.9398)
			(end -0.508 -0.9398)
			(stroke
				(width 0.1524)
				(type default)
			)
			(layer "F.SilkS")
		)
		(fp_line
			(start -0.508 -0.9398)
			(end -0.508 0.9398)
			(stroke
				(width 0.1524)
				(type default)
			)
			(layer "F.SilkS")
		)
		(fp_rect
			(start -0.508 0.9398)
			(end 0.508 -0.9398)
			(stroke
				(width 0)
				(type default)
			)
			(fill no)
			(layer "F.CrtYd")
		)
		(fp_rect
			(start -0.508 0.9398)
			(end 0.508 -0.9398)
			(stroke
				(width 0)
				(type default)
			)
			(fill no)
			(layer "F.Fab")
		)
		(pad "1" smd custom
			(at 0 -0.4445 90)
			(size 0.1397 0.1397)
			(layers "F.Cu" "F.Mask" "F.Paste")
			(net "P3V3")
			(options
				(clearance outline)
				(anchor circle)
			)
			(primitives
				(gr_poly
					(pts
						(arc
							(start -0.1778 -0.2794)
							(mid -0.249642 -0.249642)
							(end -0.2794 -0.1778)
						)
						(arc
							(start -0.2794 0.1778)
							(mid -0.249642 0.249642)
							(end -0.1778 0.2794)
						)
						(arc
							(start 0.1778 0.2794)
							(mid 0.249642 0.249642)
							(end 0.2794 0.1778)
						)
						(arc
							(start 0.2794 -0.1778)
							(mid 0.249642 -0.249642)
							(end 0.1778 -0.2794)
						)
					)
					(width 0)
					(fill yes)
				)
			)
		)
		(pad "2" smd custom
			(at 0 0.4445 90)
			(size 0.1397 0.1397)
			(layers "F.Cu" "F.Mask" "F.Paste")
			(net "SAS_EXP_A_PWR14")
			(options
				(clearance outline)
				(anchor circle)
			)
			(primitives
				(gr_poly
					(pts
						(arc
							(start -0.1778 -0.2794)
							(mid -0.249642 -0.249642)
							(end -0.2794 -0.1778)
						)
						(arc
							(start -0.2794 0.1778)
							(mid -0.249642 0.249642)
							(end -0.1778 0.2794)
						)
						(arc
							(start 0.1778 0.2794)
							(mid 0.249642 0.249642)
							(end 0.2794 0.1778)
						)
						(arc
							(start 0.2794 -0.1778)
							(mid 0.249642 -0.249642)
							(end 0.1778 -0.2794)
						)
					)
					(width 0)
					(fill yes)
				)
			)
		)
	)
	(footprint ""
		(layer "F.Cu")
		(at 72.389746 -87.2617)
		(property "Reference" "R457"
			(at 0 0 0)
			(layer "F.SilkS")
			(hide yes)
			(effects
				(font
					(size 1.27 1.27)
				)
			)
		)
		(property "Value" "4K7R2J-2-GP"
			(at 0.064008 -3.993896 0)
			(unlocked yes)
			(layer "F.Fab")
			(hide yes)
			(effects
				(font
					(size 1.016 1.016)
					(thickness 0.1524)
				)
			)
		)
		(property "Device Type" "R402H16"
			(at 0.064008 -5.517896 0)
			(unlocked yes)
			(layer "F.Fab")
			(hide yes)
			(effects
				(font
					(size 1.016 1.016)
					(thickness 0.1524)
				)
			)
		)
		(duplicate_pad_numbers_are_jumpers no)
		(fp_line
			(start -0.508 -0.9398)
			(end -0.508 0.9398)
			(stroke
				(width 0.1524)
				(type default)
			)
			(layer "F.SilkS")
		)
		(fp_line
			(start 0.508 -0.9398)
			(end -0.508 -0.9398)
			(stroke
				(width 0.1524)
				(type default)
			)
			(layer "F.SilkS")
		)
		(fp_rect
			(start -0.508 0.9398)
			(end 0.508 -0.9398)
			(stroke
				(width 0)
				(type default)
			)
			(fill no)
			(layer "F.CrtYd")
		)
		(fp_rect
			(start -0.508 0.9398)
			(end 0.508 -0.9398)
			(stroke
				(width 0)
				(type default)
			)
			(fill no)
			(layer "F.Fab")
		)
		(pad "1" smd custom
			(at 0 -0.4445)
			(size 0.1397 0.1397)
			(layers "F.Cu" "F.Mask" "F.Paste")
			(net "P3V3")
			(options
				(clearance outline)
				(anchor circle)
			)
			(primitives
				(gr_poly
					(pts
						(arc
							(start -0.1778 -0.2794)
							(mid -0.249642 -0.249642)
							(end -0.2794 -0.1778)
						)
						(arc
							(start -0.2794 0.1778)
							(mid -0.249642 0.249642)
							(end -0.1778 0.2794)
						)
						(arc
							(start 0.1778 0.2794)
							(mid 0.249642 0.249642)
							(end 0.2794 0.1778)
						)
						(arc
							(start 0.2794 -0.1778)
							(mid 0.249642 -0.249642)
							(end 0.1778 -0.2794)
						)
					)
					(width 0)
					(fill yes)
				)
			)
		)
		(pad "2" smd custom
			(at 0 0.4445)
			(size 0.1397 0.1397)
			(layers "F.Cu" "F.Mask" "F.Paste")
			(net "SAS2X28_B_HDD9_FLT")
			(options
				(clearance outline)
				(anchor circle)
			)
			(primitives
				(gr_poly
					(pts
						(arc
							(start -0.1778 -0.2794)
							(mid -0.249642 -0.249642)
							(end -0.2794 -0.1778)
						)
						(arc
							(start -0.2794 0.1778)
							(mid -0.249642 0.249642)
							(end -0.1778 0.2794)
						)
						(arc
							(start 0.1778 0.2794)
							(mid 0.249642 0.249642)
							(end 0.2794 0.1778)
						)
						(arc
							(start 0.2794 -0.1778)
							(mid 0.249642 -0.249642)
							(end 0.1778 -0.2794)
						)
					)
					(width 0)
					(fill yes)
				)
			)
		)
	)
	(footprint ""
		(layer "F.Cu")
		(at 14.604746 -52.7177 -90)
		(property "Reference" "R298"
			(at 0 0 270)
			(layer "F.SilkS")
			(hide yes)
			(effects
				(font
					(size 1.27 1.27)
				)
			)
		)
		(property "Value" "0R2J-2-GP"
			(at 0.064008 -3.993896 270)
			(unlocked yes)
			(layer "F.Fab")
			(hide yes)
			(effects
				(font
					(size 1.016 1.016)
					(thickness 0.1524)
				)
			)
		)
		(property "Device Type" "R402H16"
			(at 0.064008 -5.517896 270)
			(unlocked yes)
			(layer "F.Fab")
			(hide yes)
			(effects
				(font
					(size 1.016 1.016)
					(thickness 0.1524)
				)
			)
		)
		(duplicate_pad_numbers_are_jumpers no)
		(fp_line
			(start -0.508 -0.9398)
			(end -0.508 0.9398)
			(stroke
				(width 0.1524)
				(type default)
			)
			(layer "F.SilkS")
		)
		(fp_line
			(start 0.508 -0.9398)
			(end -0.508 -0.9398)
			(stroke
				(width 0.1524)
				(type default)
			)
			(layer "F.SilkS")
		)
		(fp_rect
			(start -0.508 0.9398)
			(end 0.508 -0.9398)
			(stroke
				(width 0)
				(type default)
			)
			(fill no)
			(layer "F.CrtYd")
		)
		(fp_rect
			(start -0.508 0.9398)
			(end 0.508 -0.9398)
			(stroke
				(width 0)
				(type default)
			)
			(fill no)
			(layer "F.Fab")
		)
		(pad "1" smd custom
			(at 0 -0.4445 270)
			(size 0.1397 0.1397)
			(layers "F.Cu" "F.Mask" "F.Paste")
			(net "DRV_ACT_NET14")
			(options
				(clearance outline)
				(anchor circle)
			)
			(primitives
				(gr_poly
					(pts
						(arc
							(start -0.1778 -0.2794)
							(mid -0.249642 -0.249642)
							(end -0.2794 -0.1778)
						)
						(arc
							(start -0.2794 0.1778)
							(mid -0.249642 0.249642)
							(end -0.1778 0.2794)
						)
						(arc
							(start 0.1778 0.2794)
							(mid 0.249642 0.249642)
							(end 0.2794 0.1778)
						)
						(arc
							(start 0.2794 -0.1778)
							(mid 0.249642 -0.249642)
							(end 0.1778 -0.2794)
						)
					)
					(width 0)
					(fill yes)
				)
			)
		)
		(pad "2" smd custom
			(at 0 0.4445 270)
			(size 0.1397 0.1397)
			(layers "F.Cu" "F.Mask" "F.Paste")
			(net "DRIVE_ACT_14")
			(options
				(clearance outline)
				(anchor circle)
			)
			(primitives
				(gr_poly
					(pts
						(arc
							(start -0.1778 -0.2794)
							(mid -0.249642 -0.249642)
							(end -0.2794 -0.1778)
						)
						(arc
							(start -0.2794 0.1778)
							(mid -0.249642 0.249642)
							(end -0.1778 0.2794)
						)
						(arc
							(start 0.1778 0.2794)
							(mid 0.249642 0.249642)
							(end 0.2794 0.1778)
						)
						(arc
							(start 0.2794 -0.1778)
							(mid 0.249642 -0.249642)
							(end 0.1778 -0.2794)
						)
					)
					(width 0)
					(fill yes)
				)
			)
		)
	)
	(footprint ""
		(layer "F.Cu")
		(at 8.788146 -403.9489)
		(property "Reference" "R355"
			(at 0 0 0)
			(layer "F.SilkS")
			(hide yes)
			(effects
				(font
					(size 1.27 1.27)
				)
			)
		)
		(property "Value" "10KR2F-2-GP"
			(at 0.064008 -3.993896 0)
			(unlocked yes)
			(layer "F.Fab")
			(hide yes)
			(effects
				(font
					(size 1.016 1.016)
					(thickness 0.1524)
				)
			)
		)
		(property "Device Type" "R402H16"
			(at 0.064008 -5.517896 0)
			(unlocked yes)
			(layer "F.Fab")
			(hide yes)
			(effects
				(font
					(size 1.016 1.016)
					(thickness 0.1524)
				)
			)
		)
		(duplicate_pad_numbers_are_jumpers no)
		(fp_line
			(start -0.508 -0.9398)
			(end -0.508 0.9398)
			(stroke
				(width 0.1524)
				(type default)
			)
			(layer "F.SilkS")
		)
		(fp_line
			(start 0.508 -0.9398)
			(end -0.508 -0.9398)
			(stroke
				(width 0.1524)
				(type default)
			)
			(layer "F.SilkS")
		)
		(fp_rect
			(start -0.508 0.9398)
			(end 0.508 -0.9398)
			(stroke
				(width 0)
				(type default)
			)
			(fill no)
			(layer "F.CrtYd")
		)
		(fp_rect
			(start -0.508 0.9398)
			(end 0.508 -0.9398)
			(stroke
				(width 0)
				(type default)
			)
			(fill no)
			(layer "F.Fab")
		)
		(pad "1" smd custom
			(at 0 -0.4445)
			(size 0.1397 0.1397)
			(layers "F.Cu" "F.Mask" "F.Paste")
			(net "P3V3")
			(options
				(clearance outline)
				(anchor circle)
			)
			(primitives
				(gr_poly
					(pts
						(arc
							(start -0.1778 -0.2794)
							(mid -0.249642 -0.249642)
							(end -0.2794 -0.1778)
						)
						(arc
							(start -0.2794 0.1778)
							(mid -0.249642 0.249642)
							(end -0.1778 0.2794)
						)
						(arc
							(start 0.1778 0.2794)
							(mid 0.249642 0.249642)
							(end 0.2794 0.1778)
						)
						(arc
							(start 0.2794 -0.1778)
							(mid 0.249642 -0.249642)
							(end 0.1778 -0.2794)
						)
					)
					(width 0)
					(fill yes)
				)
			)
		)
		(pad "2" smd custom
			(at 0 0.4445)
			(size 0.1397 0.1397)
			(layers "F.Cu" "F.Mask" "F.Paste")
			(net "TEMP_SENSOR_A_ADDR0&ID")
			(options
				(clearance outline)
				(anchor circle)
			)
			(primitives
				(gr_poly
					(pts
						(arc
							(start -0.1778 -0.2794)
							(mid -0.249642 -0.249642)
							(end -0.2794 -0.1778)
						)
						(arc
							(start -0.2794 0.1778)
							(mid -0.249642 0.249642)
							(end -0.1778 0.2794)
						)
						(arc
							(start 0.1778 0.2794)
							(mid 0.249642 0.249642)
							(end 0.2794 0.1778)
						)
						(arc
							(start 0.2794 -0.1778)
							(mid 0.249642 -0.249642)
							(end 0.1778 -0.2794)
						)
					)
					(width 0)
					(fill yes)
				)
			)
		)
	)
	(footprint ""
		(layer "F.Cu")
		(at 212.724746 -42.5577 90)
		(property "Reference" "C343"
			(at 0 0 90)
			(layer "F.SilkS")
			(hide yes)
			(effects
				(font
					(size 1.27 1.27)
				)
			)
		)
		(property "Value" "SCD1U10V2KX-5GP"
			(at 1.1811 -2.7051 90)
			(unlocked yes)
			(layer "F.Fab")
			(hide yes)
			(effects
				(font
					(size 1.016 1.016)
					(thickness 0.1524)
				)
			)
		)
		(property "Device Type" "C402H22"
			(at 1.1811 -4.2291 90)
			(unlocked yes)
			(layer "F.Fab")
			(hide yes)
			(effects
				(font
					(size 1.016 1.016)
					(thickness 0.1524)
				)
			)
		)
		(duplicate_pad_numbers_are_jumpers no)
		(fp_rect
			(start -0.4318 0.9525)
			(end 0.4318 -0.9525)
			(stroke
				(width 0)
				(type default)
			)
			(fill no)
			(layer "F.CrtYd")
		)
		(fp_rect
			(start -0.4318 0.9525)
			(end 0.4318 -0.9525)
			(stroke
				(width 0)
				(type default)
			)
			(fill no)
			(layer "F.Fab")
		)
		(pad "1" smd custom
			(at 0 -0.4445 90)
			(size 0.1524 0.1524)
			(layers "F.Cu" "F.Mask" "F.Paste")
			(net "P3V3")
			(options
				(clearance outline)
				(anchor circle)
			)
			(primitives
				(gr_poly
					(pts
						(arc
							(start 0.3048 -0.2032)
							(mid 0.275042 -0.275042)
							(end 0.2032 -0.3048)
						)
						(arc
							(start -0.2032 -0.3048)
							(mid -0.275042 -0.275042)
							(end -0.3048 -0.2032)
						)
						(arc
							(start -0.3048 0.2032)
							(mid -0.275042 0.275042)
							(end -0.2032 0.3048)
						)
						(arc
							(start 0.2032 0.3048)
							(mid 0.275042 0.275042)
							(end 0.3048 0.2032)
						)
					)
					(width 0)
					(fill yes)
				)
			)
		)
		(pad "2" smd custom
			(at 0 0.4445 90)
			(size 0.1524 0.1524)
			(layers "F.Cu" "F.Mask" "F.Paste")
			(net "GND")
			(options
				(clearance outline)
				(anchor circle)
			)
			(primitives
				(gr_poly
					(pts
						(arc
							(start 0.3048 -0.2032)
							(mid 0.275042 -0.275042)
							(end 0.2032 -0.3048)
						)
						(arc
							(start -0.2032 -0.3048)
							(mid -0.275042 -0.275042)
							(end -0.3048 -0.2032)
						)
						(arc
							(start -0.3048 0.2032)
							(mid -0.275042 0.275042)
							(end -0.2032 0.3048)
						)
						(arc
							(start 0.2032 0.3048)
							(mid 0.275042 0.275042)
							(end 0.3048 0.2032)
						)
					)
					(width 0)
					(fill yes)
				)
			)
		)
	)
	(footprint ""
		(layer "F.Cu")
		(at 217.888058 -386.028184 180)
		(property "Reference" "C122"
			(at 0 0 180)
			(layer "F.SilkS")
			(hide yes)
			(effects
				(font
					(size 1.27 1.27)
				)
			)
		)
		(property "Value" "SC1U16V3KX-5GP"
			(at 0 -2.8194 180)
			(unlocked yes)
			(layer "F.Fab")
			(hide yes)
			(effects
				(font
					(size 1.016 1.016)
					(thickness 0.1524)
				)
			)
		)
		(property "Device Type" "C603H36"
			(at 0 -4.3434 180)
			(unlocked yes)
			(layer "F.Fab")
			(hide yes)
			(effects
				(font
					(size 1.016 1.016)
					(thickness 0.1524)
				)
			)
		)
		(duplicate_pad_numbers_are_jumpers no)
		(fp_line
			(start 0.508 0)
			(end -0.508 0)
			(stroke
				(width 0.2032)
				(type default)
			)
			(layer "F.SilkS")
		)
		(fp_rect
			(start -0.5842 1.3335)
			(end 0.5842 -1.3335)
			(stroke
				(width 0)
				(type default)
			)
			(fill no)
			(layer "F.CrtYd")
		)
		(fp_rect
			(start -0.5842 1.3335)
			(end 0.5842 -1.3335)
			(stroke
				(width 0)
				(type default)
			)
			(fill no)
			(layer "F.Fab")
		)
		(pad "1" smd custom
			(at 0 -0.762 180)
			(size 0.2159 0.2159)
			(layers "F.Cu" "F.Mask" "F.Paste")
			(net "P5V_HDD1")
			(options
				(clearance outline)
				(anchor circle)
			)
			(primitives
				(gr_poly
					(pts
						(arc
							(start -0.3302 -0.4318)
							(mid -0.402042 -0.402042)
							(end -0.4318 -0.3302)
						)
						(arc
							(start -0.4318 0.3302)
							(mid -0.402042 0.402042)
							(end -0.3302 0.4318)
						)
						(arc
							(start 0.3302 0.4318)
							(mid 0.402042 0.402042)
							(end 0.4318 0.3302)
						)
						(arc
							(start 0.4318 -0.3302)
							(mid 0.402042 -0.402042)
							(end 0.3302 -0.4318)
						)
					)
					(width 0)
					(fill yes)
				)
			)
		)
		(pad "2" smd custom
			(at 0 0.762 180)
			(size 0.2159 0.2159)
			(layers "F.Cu" "F.Mask" "F.Paste")
			(net "GND")
			(options
				(clearance outline)
				(anchor circle)
			)
			(primitives
				(gr_poly
					(pts
						(arc
							(start -0.3302 -0.4318)
							(mid -0.402042 -0.402042)
							(end -0.4318 -0.3302)
						)
						(arc
							(start -0.4318 0.3302)
							(mid -0.402042 0.402042)
							(end -0.3302 0.4318)
						)
						(arc
							(start 0.3302 0.4318)
							(mid 0.402042 0.402042)
							(end 0.4318 0.3302)
						)
						(arc
							(start 0.4318 -0.3302)
							(mid 0.402042 -0.402042)
							(end 0.3302 -0.4318)
						)
					)
					(width 0)
					(fill yes)
				)
			)
		)
	)
)
